(kicad_pcb
	(version 20260206)
	(generator "pcbnew")
	(generator_version "10.0")
	(general
		(thickness 1.6)
		(legacy_teardrops no)
	)
	(paper "A4")
	(title_block
		(title "peb — Lightning_PEB_BRD.brd")
		(comment 1 "Lightning (Wiwynn / Facebook NVMe JBOF) / footprints 2255-2262 of 2563")
	)
	(layers
		(0 "F.Cu" signal "TOP")
		(4 "In1.Cu" signal "L2GND")
		(6 "In2.Cu" signal "L3")
		(8 "In3.Cu" signal "L4VCC")
		(10 "In4.Cu" signal "L5VCC")
		(12 "In5.Cu" signal "L6")
		(14 "In6.Cu" signal "L7GND")
		(2 "B.Cu" signal "BOTTOM")
		(9 "F.Adhes" user "F.Adhesive")
		(11 "B.Adhes" user "B.Adhesive")
		(13 "F.Paste" user "Package Geometry/Pastemask Top")
		(15 "B.Paste" user "Package Geometry/Pastemask Bottom")
		(5 "F.SilkS" user "Ref Des/Silkscreen Top")
		(7 "B.SilkS" user "Ref Des/Silkscreen Bottom")
		(1 "F.Mask" user "Board Geometry/Soldermask Top")
		(3 "B.Mask" user "Board Geometry/Soldermask Bottom")
		(17 "Dwgs.User" user "User.Drawings")
		(19 "Cmts.User" user "User.Comments")
		(21 "Eco1.User" user "User.Eco1")
		(23 "Eco2.User" user "User.Eco2")
		(25 "Edge.Cuts" user "Board Geometry/Outline")
		(27 "Margin" user)
		(31 "F.CrtYd" user "Package Geometry/Place Bound Top")
		(29 "B.CrtYd" user "Package Geometry/Place Bound Bottom")
		(35 "F.Fab" user "Ref Des/Assembly Top")
		(33 "B.Fab" user "Ref Des/Assembly Bottom")
	)
	(footprint ""
		(layer "B.Cu")
		(at 243.5606 -56.007 90)
		(property "Reference" "C510"
			(at 0 0 90)
			(layer "B.SilkS")
			(hide yes)
			(effects
				(font
					(size 1.27 1.27)
				)
				(justify mirror)
			)
		)
		(property "Value" "SCD1U16V1KX-1-GP"
			(at 2.8321 -1.7399 90)
			(unlocked yes)
			(layer "B.Fab")
			(hide yes)
			(effects
				(font
					(size 1.016 1.016)
					(thickness 0.1524)
				)
				(justify mirror)
			)
		)
		(property "Device Type" "C0201H13"
			(at 2.8321 -3.2639 90)
			(unlocked yes)
			(layer "B.Fab")
			(hide yes)
			(effects
				(font
					(size 1.016 1.016)
					(thickness 0.1524)
				)
				(justify mirror)
			)
		)
		(duplicate_pad_numbers_are_jumpers no)
		(fp_rect
			(start 0.2794 0.6477)
			(end -0.2794 -0.6477)
			(stroke
				(width 0)
				(type default)
			)
			(fill no)
			(layer "B.CrtYd")
		)
		(fp_rect
			(start 0.2794 0.6477)
			(end -0.2794 -0.6477)
			(stroke
				(width 0)
				(type default)
			)
			(fill no)
			(layer "B.Fab")
		)
		(pad "1" smd custom
			(at 0 -0.2794 270)
			(size 0.0762 0.0762)
			(layers "B.Cu" "B.Mask" "B.Paste")
			(net "DUT_AVD_TX")
			(options
				(clearance outline)
				(anchor circle)
			)
			(primitives
				(gr_poly
					(pts
						(arc
							(start 0.1524 0.127)
							(mid 0.137521 0.162921)
							(end 0.1016 0.1778)
						)
						(arc
							(start -0.1016 0.1778)
							(mid -0.137521 0.162921)
							(end -0.1524 0.127)
						)
						(arc
							(start -0.1524 -0.127)
							(mid -0.137521 -0.162921)
							(end -0.1016 -0.1778)
						)
						(arc
							(start 0.1016 -0.1778)
							(mid 0.137521 -0.162921)
							(end 0.1524 -0.127)
						)
					)
					(width 0)
					(fill yes)
				)
			)
		)
		(pad "2" smd custom
			(at 0 0.2794 270)
			(size 0.0762 0.0762)
			(layers "B.Cu" "B.Mask" "B.Paste")
			(net "GND")
			(options
				(clearance outline)
				(anchor circle)
			)
			(primitives
				(gr_poly
					(pts
						(arc
							(start 0.1524 0.127)
							(mid 0.137521 0.162921)
							(end 0.1016 0.1778)
						)
						(arc
							(start -0.1016 0.1778)
							(mid -0.137521 0.162921)
							(end -0.1524 0.127)
						)
						(arc
							(start -0.1524 -0.127)
							(mid -0.137521 -0.162921)
							(end -0.1016 -0.1778)
						)
						(arc
							(start 0.1016 -0.1778)
							(mid 0.137521 -0.162921)
							(end 0.1524 -0.127)
						)
					)
					(width 0)
					(fill yes)
				)
			)
		)
	)
	(footprint ""
		(layer "B.Cu")
		(at 182.07482 -12.4714 -90)
		(property "Reference" "R2937"
			(at 0 0 90)
			(layer "B.SilkS")
			(hide yes)
			(effects
				(font
					(size 1.27 1.27)
				)
				(justify mirror)
			)
		)
		(property "Value" "0R2J-2-GP"
			(at -0.064008 -3.993896 270)
			(unlocked yes)
			(layer "B.Fab")
			(hide yes)
			(effects
				(font
					(size 1.016 1.016)
					(thickness 0.1524)
				)
				(justify mirror)
			)
		)
		(property "Device Type" "R402H16"
			(at -0.064008 -5.517896 270)
			(unlocked yes)
			(layer "B.Fab")
			(hide yes)
			(effects
				(font
					(size 1.016 1.016)
					(thickness 0.1524)
				)
				(justify mirror)
			)
		)
		(duplicate_pad_numbers_are_jumpers no)
		(fp_line
			(start -0.508 -0.9398)
			(end 0.508 -0.9398)
			(stroke
				(width 0.1524)
				(type default)
			)
			(layer "B.SilkS")
		)
		(fp_line
			(start 0.508 -0.9398)
			(end 0.508 0.9398)
			(stroke
				(width 0.1524)
				(type default)
			)
			(layer "B.SilkS")
		)
		(fp_rect
			(start 0.508 0.9398)
			(end -0.508 -0.9398)
			(stroke
				(width 0)
				(type default)
			)
			(fill no)
			(layer "B.CrtYd")
		)
		(fp_rect
			(start 0.508 0.9398)
			(end -0.508 -0.9398)
			(stroke
				(width 0)
				(type default)
			)
			(fill no)
			(layer "B.Fab")
		)
		(pad "1" smd custom
			(at 0 -0.4445 90)
			(size 0.1397 0.1397)
			(layers "B.Cu" "B.Mask" "B.Paste")
			(net "PCIE_REFCLK_H3_P")
			(options
				(clearance outline)
				(anchor circle)
			)
			(primitives
				(gr_poly
					(pts
						(arc
							(start -0.1778 0.2794)
							(mid -0.249642 0.249642)
							(end -0.2794 0.1778)
						)
						(arc
							(start -0.2794 -0.1778)
							(mid -0.249642 -0.249642)
							(end -0.1778 -0.2794)
						)
						(arc
							(start 0.1778 -0.2794)
							(mid 0.249642 -0.249642)
							(end 0.2794 -0.1778)
						)
						(arc
							(start 0.2794 0.1778)
							(mid 0.249642 0.249642)
							(end 0.1778 0.2794)
						)
					)
					(width 0)
					(fill yes)
				)
			)
		)
		(pad "2" smd custom
			(at 0 0.4445 90)
			(size 0.1397 0.1397)
			(layers "B.Cu" "B.Mask" "B.Paste")
			(net "PCIE_REFCLK_H3_P_R")
			(options
				(clearance outline)
				(anchor circle)
			)
			(primitives
				(gr_poly
					(pts
						(arc
							(start -0.1778 0.2794)
							(mid -0.249642 0.249642)
							(end -0.2794 0.1778)
						)
						(arc
							(start -0.2794 -0.1778)
							(mid -0.249642 -0.249642)
							(end -0.1778 -0.2794)
						)
						(arc
							(start 0.1778 -0.2794)
							(mid 0.249642 -0.249642)
							(end 0.2794 -0.1778)
						)
						(arc
							(start 0.2794 0.1778)
							(mid 0.249642 0.249642)
							(end 0.1778 0.2794)
						)
					)
					(width 0)
					(fill yes)
				)
			)
		)
	)
	(footprint ""
		(layer "B.Cu")
		(at 79.166212 -186.545474)
		(property "Reference" "R3218"
			(at 0 0 0)
			(layer "B.SilkS")
			(hide yes)
			(effects
				(font
					(size 1.27 1.27)
				)
				(justify mirror)
			)
		)
		(property "Value" "0R2J-2-GP"
			(at -0.064008 -3.993896 0)
			(unlocked yes)
			(layer "B.Fab")
			(hide yes)
			(effects
				(font
					(size 1.016 1.016)
					(thickness 0.1524)
				)
				(justify mirror)
			)
		)
		(property "Device Type" "R402H16"
			(at -0.064008 -5.517896 0)
			(unlocked yes)
			(layer "B.Fab")
			(hide yes)
			(effects
				(font
					(size 1.016 1.016)
					(thickness 0.1524)
				)
				(justify mirror)
			)
		)
		(duplicate_pad_numbers_are_jumpers no)
		(fp_line
			(start -0.508 -0.9398)
			(end 0.508 -0.9398)
			(stroke
				(width 0.1524)
				(type default)
			)
			(layer "B.SilkS")
		)
		(fp_line
			(start 0.508 -0.9398)
			(end 0.508 0.9398)
			(stroke
				(width 0.1524)
				(type default)
			)
			(layer "B.SilkS")
		)
		(fp_rect
			(start 0.508 0.9398)
			(end -0.508 -0.9398)
			(stroke
				(width 0)
				(type default)
			)
			(fill no)
			(layer "B.CrtYd")
		)
		(fp_rect
			(start 0.508 0.9398)
			(end -0.508 -0.9398)
			(stroke
				(width 0)
				(type default)
			)
			(fill no)
			(layer "B.Fab")
		)
		(pad "1" smd custom
			(at 0 -0.4445 180)
			(size 0.1397 0.1397)
			(layers "B.Cu" "B.Mask" "B.Paste")
			(net "SSD_PERST_Y5")
			(options
				(clearance outline)
				(anchor circle)
			)
			(primitives
				(gr_poly
					(pts
						(arc
							(start -0.1778 0.2794)
							(mid -0.249642 0.249642)
							(end -0.2794 0.1778)
						)
						(arc
							(start -0.2794 -0.1778)
							(mid -0.249642 -0.249642)
							(end -0.1778 -0.2794)
						)
						(arc
							(start 0.1778 -0.2794)
							(mid 0.249642 -0.249642)
							(end 0.2794 -0.1778)
						)
						(arc
							(start 0.2794 0.1778)
							(mid 0.249642 0.249642)
							(end 0.1778 0.2794)
						)
					)
					(width 0)
					(fill yes)
				)
			)
		)
		(pad "2" smd custom
			(at 0 0.4445 180)
			(size 0.1397 0.1397)
			(layers "B.Cu" "B.Mask" "B.Paste")
			(net "SSD_PERST#5_R")
			(options
				(clearance outline)
				(anchor circle)
			)
			(primitives
				(gr_poly
					(pts
						(arc
							(start -0.1778 0.2794)
							(mid -0.249642 0.249642)
							(end -0.2794 0.1778)
						)
						(arc
							(start -0.2794 -0.1778)
							(mid -0.249642 -0.249642)
							(end -0.1778 -0.2794)
						)
						(arc
							(start 0.1778 -0.2794)
							(mid 0.249642 -0.249642)
							(end 0.2794 -0.1778)
						)
						(arc
							(start 0.2794 0.1778)
							(mid 0.249642 0.249642)
							(end 0.1778 0.2794)
						)
					)
					(width 0)
					(fill yes)
				)
			)
		)
	)
	(footprint ""
		(layer "B.Cu")
		(at 41.91 -118.872)
		(property "Reference" "TP296"
			(at 0 0 0)
			(layer "B.SilkS")
			(hide yes)
			(effects
				(font
					(size 1.27 1.27)
				)
				(justify mirror)
			)
		)
		(property "Value" "TPAD28-2-GP"
			(at 0.0127 -1.6637 0)
			(unlocked yes)
			(layer "B.Fab")
			(hide yes)
			(effects
				(font
					(size 1.016 1.016)
					(thickness 0.1524)
				)
				(justify mirror)
			)
		)
		(property "Device Type" "TPAD28"
			(at 0.0127 -3.1877 0)
			(unlocked yes)
			(layer "B.Fab")
			(hide yes)
			(effects
				(font
					(size 1.016 1.016)
					(thickness 0.1524)
				)
				(justify mirror)
			)
		)
		(duplicate_pad_numbers_are_jumpers no)
		(fp_poly
			(pts
				(arc
					(start 0.3556 0)
					(mid -0.3556 0)
					(end 0.3556 0)
				)
			)
			(stroke
				(width 0)
				(type default)
			)
			(fill no)
			(layer "B.CrtYd")
		)
		(fp_poly
			(pts
				(arc
					(start 0.6096 0)
					(mid -0.6096 0)
					(end 0.6096 0)
				)
			)
			(stroke
				(width 0)
				(type default)
			)
			(fill no)
			(layer "B.Fab")
		)
		(pad "1" smd circle
			(at 0 0 180)
			(size 0.7112 0.7112)
			(layers "B.Cu" "B.Mask" "B.Paste")
			(net "TP_GPIOV6")
		)
	)
	(footprint ""
		(layer "B.Cu")
		(at 48.6156 -106.6292 -90)
		(property "Reference" "R67"
			(at 0 0 90)
			(layer "B.SilkS")
			(hide yes)
			(effects
				(font
					(size 1.27 1.27)
				)
				(justify mirror)
			)
		)
		(property "Value" "0R2J-2-GP"
			(at -0.064008 -3.993896 270)
			(unlocked yes)
			(layer "B.Fab")
			(hide yes)
			(effects
				(font
					(size 1.016 1.016)
					(thickness 0.1524)
				)
				(justify mirror)
			)
		)
		(property "Device Type" "R402H16"
			(at -0.064008 -5.517896 270)
			(unlocked yes)
			(layer "B.Fab")
			(hide yes)
			(effects
				(font
					(size 1.016 1.016)
					(thickness 0.1524)
				)
				(justify mirror)
			)
		)
		(duplicate_pad_numbers_are_jumpers no)
		(fp_line
			(start -0.508 -0.9398)
			(end 0.508 -0.9398)
			(stroke
				(width 0.1524)
				(type default)
			)
			(layer "B.SilkS")
		)
		(fp_line
			(start 0.508 -0.9398)
			(end 0.508 0.9398)
			(stroke
				(width 0.1524)
				(type default)
			)
			(layer "B.SilkS")
		)
		(fp_rect
			(start 0.508 0.9398)
			(end -0.508 -0.9398)
			(stroke
				(width 0)
				(type default)
			)
			(fill no)
			(layer "B.CrtYd")
		)
		(fp_rect
			(start 0.508 0.9398)
			(end -0.508 -0.9398)
			(stroke
				(width 0)
				(type default)
			)
			(fill no)
			(layer "B.Fab")
		)
		(pad "1" smd custom
			(at 0 -0.4445 90)
			(size 0.1397 0.1397)
			(layers "B.Cu" "B.Mask" "B.Paste")
			(net "BMC_I2C14_MINI8_SCL_S")
			(options
				(clearance outline)
				(anchor circle)
			)
			(primitives
				(gr_poly
					(pts
						(arc
							(start -0.1778 0.2794)
							(mid -0.249642 0.249642)
							(end -0.2794 0.1778)
						)
						(arc
							(start -0.2794 -0.1778)
							(mid -0.249642 -0.249642)
							(end -0.1778 -0.2794)
						)
						(arc
							(start 0.1778 -0.2794)
							(mid 0.249642 -0.249642)
							(end 0.2794 -0.1778)
						)
						(arc
							(start 0.2794 0.1778)
							(mid 0.249642 0.249642)
							(end 0.1778 0.2794)
						)
					)
					(width 0)
					(fill yes)
				)
			)
		)
		(pad "2" smd custom
			(at 0 0.4445 90)
			(size 0.1397 0.1397)
			(layers "B.Cu" "B.Mask" "B.Paste")
			(net "BMC_I2C14_MINI8_SCL")
			(options
				(clearance outline)
				(anchor circle)
			)
			(primitives
				(gr_poly
					(pts
						(arc
							(start -0.1778 0.2794)
							(mid -0.249642 0.249642)
							(end -0.2794 0.1778)
						)
						(arc
							(start -0.2794 -0.1778)
							(mid -0.249642 -0.249642)
							(end -0.1778 -0.2794)
						)
						(arc
							(start 0.1778 -0.2794)
							(mid 0.249642 -0.249642)
							(end 0.2794 -0.1778)
						)
						(arc
							(start 0.2794 0.1778)
							(mid 0.249642 0.249642)
							(end 0.1778 0.2794)
						)
					)
					(width 0)
					(fill yes)
				)
			)
		)
	)
	(footprint ""
		(layer "B.Cu")
		(at 299.353732 -34.624772 180)
		(property "Reference" "C277"
			(at 0 0 0)
			(layer "B.SilkS")
			(hide yes)
			(effects
				(font
					(size 1.27 1.27)
				)
				(justify mirror)
			)
		)
		(property "Value" "SCD1U10V2KX-5GP"
			(at -1.1811 -2.7051 180)
			(unlocked yes)
			(layer "B.Fab")
			(hide yes)
			(effects
				(font
					(size 1.016 1.016)
					(thickness 0.1524)
				)
				(justify mirror)
			)
		)
		(property "Device Type" "C402H22"
			(at -1.1811 -4.2291 180)
			(unlocked yes)
			(layer "B.Fab")
			(hide yes)
			(effects
				(font
					(size 1.016 1.016)
					(thickness 0.1524)
				)
				(justify mirror)
			)
		)
		(duplicate_pad_numbers_are_jumpers no)
		(fp_rect
			(start 0.4318 0.9525)
			(end -0.4318 -0.9525)
			(stroke
				(width 0)
				(type default)
			)
			(fill no)
			(layer "B.CrtYd")
		)
		(fp_rect
			(start 0.4318 0.9525)
			(end -0.4318 -0.9525)
			(stroke
				(width 0)
				(type default)
			)
			(fill no)
			(layer "B.Fab")
		)
		(pad "1" smd custom
			(at 0 -0.4445)
			(size 0.1524 0.1524)
			(layers "B.Cu" "B.Mask" "B.Paste")
			(net "GND")
			(options
				(clearance outline)
				(anchor circle)
			)
			(primitives
				(gr_poly
					(pts
						(arc
							(start 0.3048 0.2032)
							(mid 0.275042 0.275042)
							(end 0.2032 0.3048)
						)
						(arc
							(start -0.2032 0.3048)
							(mid -0.275042 0.275042)
							(end -0.3048 0.2032)
						)
						(arc
							(start -0.3048 -0.2032)
							(mid -0.275042 -0.275042)
							(end -0.2032 -0.3048)
						)
						(arc
							(start 0.2032 -0.3048)
							(mid 0.275042 -0.275042)
							(end 0.3048 -0.2032)
						)
					)
					(width 0)
					(fill yes)
				)
			)
		)
		(pad "2" smd custom
			(at 0 0.4445)
			(size 0.1524 0.1524)
			(layers "B.Cu" "B.Mask" "B.Paste")
			(net "P3V3_STBY")
			(options
				(clearance outline)
				(anchor circle)
			)
			(primitives
				(gr_poly
					(pts
						(arc
							(start 0.3048 0.2032)
							(mid 0.275042 0.275042)
							(end 0.2032 0.3048)
						)
						(arc
							(start -0.2032 0.3048)
							(mid -0.275042 0.275042)
							(end -0.3048 0.2032)
						)
						(arc
							(start -0.3048 -0.2032)
							(mid -0.275042 -0.275042)
							(end -0.2032 -0.3048)
						)
						(arc
							(start 0.2032 -0.3048)
							(mid 0.275042 -0.275042)
							(end 0.3048 -0.2032)
						)
					)
					(width 0)
					(fill yes)
				)
			)
		)
	)
	(footprint ""
		(layer "B.Cu")
		(at 178.0794 -68.453)
		(property "Reference" "PG26"
			(at 0 0 0)
			(layer "B.SilkS")
			(hide yes)
			(effects
				(font
					(size 1.27 1.27)
				)
				(justify mirror)
			)
		)
		(property "Value" "GAP-CLOSE-PWR-3-GP"
			(at -0.0254 -6.5786 0)
			(unlocked yes)
			(layer "B.Fab")
			(hide yes)
			(effects
				(font
					(size 1.016 1.016)
					(thickness 0.1524)
				)
				(justify mirror)
			)
		)
		(property "Device Type" "GAP-CLOSE-PWR-3"
			(at -0.0254 -8.255 0)
			(unlocked yes)
			(layer "B.Fab")
			(hide yes)
			(effects
				(font
					(size 1.016 1.016)
					(thickness 0.1524)
				)
				(justify mirror)
			)
		)
		(duplicate_pad_numbers_are_jumpers no)
		(fp_rect
			(start 0.7112 0.4572)
			(end -0.7112 -0.4572)
			(stroke
				(width 0)
				(type default)
			)
			(fill no)
			(layer "B.CrtYd")
		)
		(fp_poly
			(pts
				(xy 0.7112 -0.4572) (xy -0.7112 -0.4572) (xy -0.7112 0.4572) (xy 0.7112 0.4572)
			)
			(stroke
				(width 0)
				(type default)
			)
			(fill no)
			(layer "B.Fab")
		)
		(pad "1" smd rect
			(at 0.3048 0 180)
			(size 0.6604 0.762)
			(layers "B.Cu" "B.Mask" "B.Paste")
			(net "DUT_AVD_PCIE")
		)
		(pad "2" smd rect
			(at -0.3048 0 180)
			(size 0.6604 0.762)
			(layers "B.Cu" "B.Mask" "B.Paste")
			(net "P0V9")
		)
	)
	(footprint ""
		(layer "B.Cu")
		(at 250.5964 -60.071)
		(property "Reference" "C599"
			(at 0 0 0)
			(layer "B.SilkS")
			(hide yes)
			(effects
				(font
					(size 1.27 1.27)
				)
				(justify mirror)
			)
		)
		(property "Value" "SCD1U16V1KX-1-GP"
			(at 2.8321 -1.7399 0)
			(unlocked yes)
			(layer "B.Fab")
			(hide yes)
			(effects
				(font
					(size 1.016 1.016)
					(thickness 0.1524)
				)
				(justify mirror)
			)
		)
		(property "Device Type" "C0201H13"
			(at 2.8321 -3.2639 0)
			(unlocked yes)
			(layer "B.Fab")
			(hide yes)
			(effects
				(font
					(size 1.016 1.016)
					(thickness 0.1524)
				)
				(justify mirror)
			)
		)
		(duplicate_pad_numbers_are_jumpers no)
		(fp_rect
			(start 0.2794 0.6477)
			(end -0.2794 -0.6477)
			(stroke
				(width 0)
				(type default)
			)
			(fill no)
			(layer "B.CrtYd")
		)
		(fp_rect
			(start 0.2794 0.6477)
			(end -0.2794 -0.6477)
			(stroke
				(width 0)
				(type default)
			)
			(fill no)
			(layer "B.Fab")
		)
		(pad "1" smd custom
			(at 0 -0.2794 180)
			(size 0.0762 0.0762)
			(layers "B.Cu" "B.Mask" "B.Paste")
			(net "DUT_AVD_PCIE")
			(options
				(clearance outline)
				(anchor circle)
			)
			(primitives
				(gr_poly
					(pts
						(arc
							(start 0.1524 0.127)
							(mid 0.137521 0.162921)
							(end 0.1016 0.1778)
						)
						(arc
							(start -0.1016 0.1778)
							(mid -0.137521 0.162921)
							(end -0.1524 0.127)
						)
						(arc
							(start -0.1524 -0.127)
							(mid -0.137521 -0.162921)
							(end -0.1016 -0.1778)
						)
						(arc
							(start 0.1016 -0.1778)
							(mid 0.137521 -0.162921)
							(end 0.1524 -0.127)
						)
					)
					(width 0)
					(fill yes)
				)
			)
		)
		(pad "2" smd custom
			(at 0 0.2794 180)
			(size 0.0762 0.0762)
			(layers "B.Cu" "B.Mask" "B.Paste")
			(net "GND")
			(options
				(clearance outline)
				(anchor circle)
			)
			(primitives
				(gr_poly
					(pts
						(arc
							(start 0.1524 0.127)
							(mid 0.137521 0.162921)
							(end 0.1016 0.1778)
						)
						(arc
							(start -0.1016 0.1778)
							(mid -0.137521 0.162921)
							(end -0.1524 0.127)
						)
						(arc
							(start -0.1524 -0.127)
							(mid -0.137521 -0.162921)
							(end -0.1016 -0.1778)
						)
						(arc
							(start 0.1016 -0.1778)
							(mid 0.137521 -0.162921)
							(end 0.1524 -0.127)
						)
					)
					(width 0)
					(fill yes)
				)
			)
		)
	)
)
